# S9S_MB_2U (Grand Teton) — schematic netlist excerpt (pin names and nets, part order shuffled) for the footprints in the layout excerpt that follows; sources: Cadence DE-HDL packaged netlist, KiCad conversion of 03242023_DA0F0TMBIJ0_F0T_Motherboard_J_brd_V01_OCP.brd

PU51_P1_2  ISL99390FRZTR5935  ISL99390FRZ-TR5935 IC  pkg QFN21_6X5XB  page 293
  VOS  = PVCCINFAON_CPU1_VOS2
  AGND  = GND
  VCC  = PVCCINFAON_CPU1_VDD2
  PVCC  = PVCCFA_EHV_CPU1_PVCC
  PGND1  = GND
  GL1  = NC
  PGND2  = GND
  SW  = SW_PVCCINFAON_CPU1_SW2
  VIN1  = SW_P12V_PVCCINFAON_CPU1_FLT
  VIN2  = SW_P12V_PVCCINFAON_CPU1_FLT
  DNC  = NC
  PHASE  = SW_PVCCINFAON_CPU1_BOOTR2
  BOOT  = SW_PVCCINFAON_CPU1_BOOT2
  PWM  = PVCCINFAON_CPU1_APWM2
  EN  = PVCCINFAON_CPU1_VDD2
  TOUT_FLT  = PVCCINFAON_CPU1_ATSEN
  LSET  = PVCCINFAON_CPU1_LSET2
  IOUT  = PVCCINFAON_CPU1_ACSP2
  REFIN  = PVCCINFAON_CPU1_VREF
  PGND3  = GND
  GL2  = NC

(kicad_pcb
	(version 20260206)
	(generator "pcbnew")
	(generator_version "10.0")
	(general
		(thickness 1.6)
		(legacy_teardrops no)
	)
	(paper "A4")
	(title_block
		(title "03242023_DA0F0TMBIJ0_F0T_Motherboard_J_brd_V01_OCP.brd")
		(comment 1 "Grand Teton / footprints 4012-4012 of 6105")
	)
	(layers
		(0 "F.Cu" signal "TOP")
		(4 "In1.Cu" signal "GND")
		(6 "In2.Cu" signal "IN1")
		(8 "In3.Cu" signal "GND1")
		(10 "In4.Cu" signal "IN2")
		(12 "In5.Cu" signal "GND2")
		(14 "In6.Cu" signal "IN3")
		(16 "In7.Cu" signal "GND3")
		(18 "In8.Cu" signal "VCC")
		(20 "In9.Cu" signal "VCC1")
		(22 "In10.Cu" signal "GND4")
		(24 "In11.Cu" signal "IN4")
		(26 "In12.Cu" signal "GND5")
		(28 "In13.Cu" signal "IN5")
		(30 "In14.Cu" signal "GND6")
		(32 "In15.Cu" signal "IN6")
		(34 "In16.Cu" signal "GND7")
		(2 "B.Cu" signal "BOTTOM")
		(9 "F.Adhes" user "F.Adhesive")
		(11 "B.Adhes" user "B.Adhesive")
		(13 "F.Paste" user "Package Geometry/Pastemask Top")
		(15 "B.Paste" user "Package Geometry/Pastemask Bottom")
		(5 "F.SilkS" user "Ref Des/Silkscreen Top")
		(7 "B.SilkS" user "Ref Des/Silkscreen Bottom")
		(1 "F.Mask" user "Board Geometry/Soldermask Top")
		(3 "B.Mask" user "Board Geometry/Soldermask Bottom")
		(17 "Dwgs.User" user "User.Drawings")
		(19 "Cmts.User" user "User.Comments")
		(21 "Eco1.User" user "User.Eco1")
		(23 "Eco2.User" user "User.Eco2")
		(25 "Edge.Cuts" user "Board Geometry/Outline")
		(27 "Margin" user)
		(31 "F.CrtYd" user "Package Geometry/Place Bound Top")
		(29 "B.CrtYd" user "Package Geometry/Place Bound Bottom")
		(35 "F.Fab" user "Ref Des/Assembly Top")
		(33 "B.Fab" user "Ref Des/Assembly Bottom")
	)
	(footprint ""
		(layer "F.Cu")
		(at 54.89956 -147.84197 90)
		(property "Reference" "PU51_P1_2"
			(at -5.795772 -4.134358 0)
			(unlocked yes)
			(layer "F.SilkS")
			(effects
				(font
					(size 0.7874 0.5842)
					(thickness 0.1524)
				)
				(justify left)
			)
		)
		(property "Value" ""
			(at 0 0 90)
			(layer "F.Fab")
			(effects
				(font
					(size 1.27 1.27)
				)
			)
		)
		(duplicate_pad_numbers_are_jumpers no)
		(fp_line
			(start 2.500122 -2.999994)
			(end 2.500122 -2.44348)
			(stroke
				(width 0.1524)
				(type default)
			)
			(layer "F.SilkS")
		)
		(fp_line
			(start 2.31394 -2.999994)
			(end 2.500122 -2.999994)
			(stroke
				(width 0.1524)
				(type default)
			)
			(layer "F.SilkS")
		)
		(fp_line
			(start -2.500122 -2.999994)
			(end -2.24409 -2.999994)
			(stroke
				(width 0.1524)
				(type default)
			)
			(layer "F.SilkS")
		)
		(fp_line
			(start -2.500122 -2.529078)
			(end -2.500122 -2.999994)
			(stroke
				(width 0.1524)
				(type default)
			)
			(layer "F.SilkS")
		)
		(fp_line
			(start -2.500122 0.6604)
			(end -2.500122 0.229108)
			(stroke
				(width 0.1524)
				(type default)
			)
			(layer "F.SilkS")
		)
		(fp_line
			(start 2.500122 2.339594)
			(end 2.500122 2.999994)
			(stroke
				(width 0.1524)
				(type default)
			)
			(layer "F.SilkS")
		)
		(fp_line
			(start 2.500122 2.999994)
			(end 2.2987 2.999994)
			(stroke
				(width 0.1524)
				(type default)
			)
			(layer "F.SilkS")
		)
		(fp_line
			(start -2.2987 2.999994)
			(end -2.500122 2.999994)
			(stroke
				(width 0.1524)
				(type default)
			)
			(layer "F.SilkS")
		)
		(fp_line
			(start -2.500122 2.999994)
			(end -2.500122 2.339594)
			(stroke
				(width 0.1524)
				(type default)
			)
			(layer "F.SilkS")
		)
		(fp_poly
			(pts
				(xy -5.099812 -2.818638) (xy -4.083812 -2.310638) (xy -5.099812 -1.802638)
			)
			(stroke
				(width 0)
				(type default)
			)
			(fill yes)
			(layer "F.SilkS")
		)
		(fp_line
			(start 2.500122 -2.999994)
			(end 2.500122 2.999994)
			(stroke
				(width 0.1)
				(type default)
			)
			(layer "F.Fab")
		)
		(fp_line
			(start -2.500122 -2.999994)
			(end 2.500122 -2.999994)
			(stroke
				(width 0.1)
				(type default)
			)
			(layer "F.Fab")
		)
		(fp_line
			(start 2.500122 2.999994)
			(end -2.500122 2.999994)
			(stroke
				(width 0.1)
				(type default)
			)
			(layer "F.Fab")
		)
		(fp_line
			(start -2.500122 2.999994)
			(end -2.500122 -2.999994)
			(stroke
				(width 0.1)
				(type default)
			)
			(layer "F.Fab")
		)
		(fp_poly
			(pts
				(xy -4.218432 -2.783078) (xy -4.218432 -1.767078) (xy -3.202432 -2.275078)
			)
			(stroke
				(width 0)
				(type default)
			)
			(fill yes)
			(layer "F.Fab")
		)
		(pad "1" smd rect
			(at -2.400046 -2.275078 180)
			(size 0.2286 0.6096)
			(layers "F.Cu" "F.Mask" "F.Paste")
			(net "PVCCINFAON_CPU1_VOS2")
		)
		(pad "2" smd rect
			(at -2.400046 -1.82499 180)
			(size 0.2286 0.6096)
			(layers "F.Cu" "F.Mask" "F.Paste")
			(net "GND")
		)
		(pad "3" smd rect
			(at -2.400046 -1.374902 180)
			(size 0.2286 0.6096)
			(layers "F.Cu" "F.Mask" "F.Paste")
			(net "PVCCINFAON_CPU1_VDD2")
		)
		(pad "4" smd rect
			(at -2.400046 -0.925068 180)
			(size 0.2286 0.6096)
			(layers "F.Cu" "F.Mask" "F.Paste")
			(net "PVCCFA_EHV_CPU1_PVCC")
		)
		(pad "5" smd rect
			(at -2.400046 -0.47498 180)
			(size 0.2286 0.6096)
			(layers "F.Cu" "F.Mask" "F.Paste")
			(net "GND")
		)
		(pad "6" smd rect
			(at -2.400046 -0.024892 180)
			(size 0.2286 0.6096)
			(layers "F.Cu" "F.Mask" "F.Paste")
			(net "Net_1932")
		)
		(pad "7_9-20_24" smd circle
			(at 0 1.150112 180)
			(size 0 0)
			(layers "F.Cu" "F.Mask" "F.Paste")
			(net "GND")
		)
		(pad "10_19" smd rect
			(at 0 2.899918 180)
			(size 0.6096 4.318)
			(layers "F.Cu" "F.Mask" "F.Paste")
			(net "SW_PVCCINFAON_CPU1_SW2")
		)
		(pad "25_29" smd rect
			(at 1.549908 -1.279906)
			(size 2.0574 2.3114)
			(layers "F.Cu" "F.Mask" "F.Paste")
			(net "SW_P12V_PVCCINFAON_CPU1_FLT")
		)
		(pad "30" smd rect
			(at 2.05994 -2.899918 90)
			(size 0.2286 0.6096)
			(layers "F.Cu" "F.Mask" "F.Paste")
			(net "SW_P12V_PVCCINFAON_CPU1_FLT")
		)
		(pad "31" smd rect
			(at 1.610106 -2.899918 90)
			(size 0.2286 0.6096)
			(layers "F.Cu" "F.Mask" "F.Paste")
			(net "Net_1931")
		)
		(pad "32" smd rect
			(at 1.160018 -2.899918 90)
			(size 0.2286 0.6096)
			(layers "F.Cu" "F.Mask" "F.Paste")
			(net "SW_PVCCINFAON_CPU1_BOOTR2")
		)
		(pad "33" smd rect
			(at 0.70993 -2.899918 90)
			(size 0.2286 0.6096)
			(layers "F.Cu" "F.Mask" "F.Paste")
			(net "SW_PVCCINFAON_CPU1_BOOT2")
		)
		(pad "34" smd rect
			(at 0.260096 -2.899918 90)
			(size 0.2286 0.6096)
			(layers "F.Cu" "F.Mask" "F.Paste")
			(net "PVCCINFAON_CPU1_APWM2")
		)
		(pad "35" smd rect
			(at -0.189992 -2.899918 90)
			(size 0.2286 0.6096)
			(layers "F.Cu" "F.Mask" "F.Paste")
			(net "PVCCINFAON_CPU1_VDD2")
		)
		(pad "36" smd rect
			(at -0.64008 -2.899918 90)
			(size 0.2286 0.6096)
			(layers "F.Cu" "F.Mask" "F.Paste")
			(net "PVCCINFAON_CPU1_ATSEN")
		)
		(pad "37" smd rect
			(at -1.089914 -2.899918 90)
			(size 0.2286 0.6096)
			(layers "F.Cu" "F.Mask" "F.Paste")
			(net "PVCCINFAON_CPU1_LSET2")
		)
		(pad "38" smd rect
			(at -1.540002 -2.899918 90)
			(size 0.2286 0.6096)
			(layers "F.Cu" "F.Mask" "F.Paste")
			(net "PVCCINFAON_CPU1_ACSP2")
		)
		(pad "39" smd rect
			(at -1.99009 -2.899918 90)
			(size 0.2286 0.6096)
			(layers "F.Cu" "F.Mask" "F.Paste")
			(net "PVCCINFAON_CPU1_VREF")
		)
		(pad "40" smd rect
			(at -0.87503 -1.27508 90)
			(size 1.7526 1.9558)
			(layers "F.Cu" "F.Mask" "F.Paste")
			(net "GND")
		)
		(pad "41" smd rect
			(at -1.525016 0.249936)
			(size 0.3048 0.4572)
			(layers "F.Cu" "F.Mask" "F.Paste")
			(net "Net_1933")
		)
		(zone
			(layer "F.Cu")
			(hatch none 0.5)
			(connect_pads
				(clearance 0)
			)
			(min_thickness 0.25)
			(keepout
				(tracks not_allowed)
				(vias allowed)
				(pads allowed)
				(copperpour not_allowed)
				(footprints allowed)
			)
			(placement
				(enabled no)
				(sheetname "")
			)
			(fill
				(thermal_gap 0.5)
				(thermal_bridge_width 0.5)
				(island_removal_mode 0)
			)
			(polygon
				(pts
					(xy 53.19268 -146.03984) (xy 54.3052 -146.03984) (xy 54.3052 -145.797524) (xy 53.19268 -145.797524)
				)
			)
		)
		(zone
			(layer "F.Cu")
			(hatch none 0.5)
			(connect_pads
				(clearance 0)
			)
			(min_thickness 0.25)
			(keepout
				(tracks not_allowed)
				(vias allowed)
				(pads allowed)
				(copperpour not_allowed)
				(footprints allowed)
			)
			(placement
				(enabled no)
				(sheetname "")
			)
			(fill
				(thermal_gap 0.5)
				(thermal_bridge_width 0.5)
				(island_removal_mode 0)
			)
			(polygon
				(pts
					(xy 57.899554 -145.341848) (xy 57.3786 -145.341848) (xy 57.150254 -145.570194) (xy 57.150254 -150.139146)
					(xy 57.3532 -150.342092) (xy 57.899554 -150.342092) (xy 57.899554 -150.05177) (xy 57.443878 -150.05177)
					(xy 57.443878 -145.63217) (xy 57.899554 -145.63217)
				)
			)
		)
	)
)
